(kicad_pcb
	(version 20260206)
	(generator "pcbnew")
	(generator_version "10.0")
	(general
		(thickness 1.6)
		(legacy_teardrops no)
	)
	(paper "A4")
	(title_block
		(title "Wiwynn_Tioga_Pass_MB.brd")
		(comment 1 "Tioga Pass / footprints 400-406 of 4770")
	)
	(layers
		(0 "F.Cu" signal "TOP")
		(4 "In1.Cu" signal "L2GND")
		(6 "In2.Cu" signal "L3")
		(8 "In3.Cu" signal "L4GND")
		(10 "In4.Cu" signal "L5")
		(12 "In5.Cu" signal "L6GND")
		(14 "In6.Cu" signal "L7VCC")
		(16 "In7.Cu" signal "L8VCC")
		(18 "In8.Cu" signal "L9GND")
		(20 "In9.Cu" signal "L10")
		(22 "In10.Cu" signal "L11GND")
		(24 "In11.Cu" signal "L12")
		(26 "In12.Cu" signal "L13GND")
		(2 "B.Cu" signal "BOTTOM")
		(9 "F.Adhes" user "F.Adhesive")
		(11 "B.Adhes" user "B.Adhesive")
		(13 "F.Paste" user "Package Geometry/Pastemask Top")
		(15 "B.Paste" user "Package Geometry/Pastemask Bottom")
		(5 "F.SilkS" user "Ref Des/Silkscreen Top")
		(7 "B.SilkS" user "Ref Des/Silkscreen Bottom")
		(1 "F.Mask" user "Board Geometry/Soldermask Top")
		(3 "B.Mask" user "Board Geometry/Soldermask Bottom")
		(17 "Dwgs.User" user "User.Drawings")
		(19 "Cmts.User" user "User.Comments")
		(21 "Eco1.User" user "User.Eco1")
		(23 "Eco2.User" user "User.Eco2")
		(25 "Edge.Cuts" user "Board Geometry/Outline")
		(27 "Margin" user)
		(31 "F.CrtYd" user "Package Geometry/Place Bound Top")
		(29 "B.CrtYd" user "Package Geometry/Place Bound Bottom")
		(35 "F.Fab" user "Ref Des/Assembly Top")
		(33 "B.Fab" user "Ref Des/Assembly Bottom")
	)
	(footprint ""
		(layer "F.Cu")
		(at 476.031814 -22.405848)
		(property "Reference" "C9F1"
			(at 0 0 0)
			(layer "F.SilkS")
			(hide yes)
			(effects
				(font
					(size 1.27 1.27)
				)
			)
		)
		(property "Value" "*"
			(at -0.0762 -6.2357 0)
			(unlocked yes)
			(layer "F.Fab")
			(hide yes)
			(effects
				(font
					(size 1.27 1.016)
					(thickness 0.1524)
				)
			)
		)
		(property "Device Type" "SC22U16V5MX-4-GP_SMD-BCG5-SC22A"
			(at -0.0762 -8.2677 0)
			(unlocked yes)
			(layer "F.Fab")
			(hide yes)
			(effects
				(font
					(size 1.27 1.016)
					(thickness 0.1524)
				)
			)
		)
		(duplicate_pad_numbers_are_jumpers no)
		(fp_line
			(start 0.635 0)
			(end -0.635 0)
			(stroke
				(width 0.508)
				(type default)
			)
			(layer "F.SilkS")
		)
		(fp_rect
			(start -0.9652 1.778)
			(end 0.9652 -1.778)
			(stroke
				(width 0)
				(type default)
			)
			(fill no)
			(layer "F.CrtYd")
		)
		(fp_poly
			(pts
				(xy -0.9652 -1.778) (xy 0.9652 -1.778) (xy 0.9652 1.778) (xy -0.9652 1.778)
			)
			(stroke
				(width 0)
				(type default)
			)
			(fill no)
			(layer "F.Fab")
		)
		(pad "1" smd rect
			(at 0 -0.9652)
			(size 1.397 1.143)
			(layers "F.Cu" "F.Mask" "F.Paste")
			(net "VR_FET_SW_P12V_STBY_P3V3_STBY")
		)
		(pad "2" smd rect
			(at 0 0.9652)
			(size 1.397 1.143)
			(layers "F.Cu" "F.Mask" "F.Paste")
			(net "GND")
		)
	)
	(footprint ""
		(layer "F.Cu")
		(at 498.620034 -137.278618 90)
		(property "Reference" "DS9A7"
			(at -0.76073 0.85344 0)
			(unlocked yes)
			(layer "F.SilkS")
			(effects
				(font
					(size 0.7874 0.5842)
					(thickness 0.1524)
				)
			)
		)
		(property "Value" ""
			(at 0 0 90)
			(layer "F.Fab")
			(effects
				(font
					(size 1.27 1.27)
				)
			)
		)
		(duplicate_pad_numbers_are_jumpers no)
		(fp_line
			(start -1.353312 -0.498094)
			(end -1.353312 0.413512)
			(stroke
				(width 0.1524)
				(type default)
			)
			(layer "F.SilkS")
		)
		(fp_line
			(start -0.87249 0.413512)
			(end -1.353312 1.246378)
			(stroke
				(width 0.1524)
				(type default)
			)
			(layer "F.SilkS")
		)
		(fp_line
			(start -1.353312 0.413512)
			(end -0.87249 0.413512)
			(stroke
				(width 0.1524)
				(type default)
			)
			(layer "F.SilkS")
		)
		(fp_line
			(start -1.834134 0.413512)
			(end -1.353312 0.413512)
			(stroke
				(width 0.1524)
				(type default)
			)
			(layer "F.SilkS")
		)
		(fp_line
			(start -1.353312 1.246378)
			(end -1.834134 0.413512)
			(stroke
				(width 0.1524)
				(type default)
			)
			(layer "F.SilkS")
		)
		(fp_line
			(start -1.834134 1.246378)
			(end -0.87249 1.246378)
			(stroke
				(width 0.1524)
				(type default)
			)
			(layer "F.SilkS")
		)
		(fp_line
			(start -1.353312 2.36982)
			(end -1.353312 1.246378)
			(stroke
				(width 0.1524)
				(type default)
			)
			(layer "F.SilkS")
		)
		(fp_rect
			(start -0.4064 1.6891)
			(end 0.4064 0.0889)
			(stroke
				(width 0)
				(type default)
			)
			(fill no)
			(layer "F.CrtYd")
		)
		(fp_line
			(start 0.4064 0.0889)
			(end 0.4064 1.6891)
			(stroke
				(width 0.1)
				(type default)
			)
			(layer "F.Fab")
		)
		(fp_line
			(start -0.4064 0.0889)
			(end 0.4064 0.0889)
			(stroke
				(width 0.1)
				(type default)
			)
			(layer "F.Fab")
		)
		(fp_line
			(start -0.87249 0.413512)
			(end -1.353312 1.246378)
			(stroke
				(width 0.1)
				(type default)
			)
			(layer "F.Fab")
		)
		(fp_line
			(start -1.353312 0.413512)
			(end -1.353312 -0.498094)
			(stroke
				(width 0.1)
				(type default)
			)
			(layer "F.Fab")
		)
		(fp_line
			(start -1.834134 0.413512)
			(end -0.87249 0.413512)
			(stroke
				(width 0.1)
				(type default)
			)
			(layer "F.Fab")
		)
		(fp_line
			(start -1.353312 1.246378)
			(end -1.834134 0.413512)
			(stroke
				(width 0.1)
				(type default)
			)
			(layer "F.Fab")
		)
		(fp_line
			(start -1.353312 1.246378)
			(end -1.353312 2.36982)
			(stroke
				(width 0.1)
				(type default)
			)
			(layer "F.Fab")
		)
		(fp_line
			(start -1.834134 1.246378)
			(end -0.87249 1.246378)
			(stroke
				(width 0.1)
				(type default)
			)
			(layer "F.Fab")
		)
		(fp_line
			(start 0.4064 1.6891)
			(end -0.4064 1.6891)
			(stroke
				(width 0.1)
				(type default)
			)
			(layer "F.Fab")
		)
		(fp_line
			(start -0.4064 1.6891)
			(end -0.4064 0.0889)
			(stroke
				(width 0.1)
				(type default)
			)
			(layer "F.Fab")
		)
		(pad "1" smd rect
			(at 0 0 90)
			(size 0.762 1.27)
			(layers "F.Cu" "F.Mask" "F.Paste")
			(net "FM_UARTSW_MSB_R_N")
		)
		(pad "2" smd rect
			(at 0 1.778 90)
			(size 0.762 1.27)
			(layers "F.Cu" "F.Mask" "F.Paste")
			(net "FM_UARTSW_MSB_N")
		)
		(zone
			(layer "F.Cu")
			(hatch none 0.5)
			(connect_pads
				(clearance 0)
			)
			(min_thickness 0.25)
			(keepout
				(tracks not_allowed)
				(vias allowed)
				(pads allowed)
				(copperpour not_allowed)
				(footprints allowed)
			)
			(placement
				(enabled no)
				(sheetname "")
			)
			(fill
				(thermal_gap 0.5)
				(thermal_bridge_width 0.5)
				(island_removal_mode 0)
			)
			(polygon
				(pts
					(xy 499.280434 -136.897618) (xy 499.280434 -137.659618) (xy 499.737634 -137.659618) (xy 499.737634 -136.897618)
				)
			)
		)
		(zone
			(layer "F.Cu")
			(hatch none 0.5)
			(connect_pads
				(clearance 0)
			)
			(min_thickness 0.25)
			(keepout
				(tracks allowed)
				(vias not_allowed)
				(pads allowed)
				(copperpour not_allowed)
				(footprints allowed)
			)
			(placement
				(enabled no)
				(sheetname "")
			)
			(fill
				(thermal_gap 0.5)
				(thermal_bridge_width 0.5)
				(island_removal_mode 0)
			)
			(polygon
				(pts
					(xy 499.737634 -136.897618) (xy 499.737634 -137.659618) (xy 499.280434 -137.659618) (xy 499.280434 -136.897618)
				)
			)
		)
	)
	(footprint ""
		(layer "F.Cu")
		(at 195.5546 -130.2512 90)
		(property "Reference" "C4B12"
			(at 0 0 90)
			(layer "F.SilkS")
			(hide yes)
			(effects
				(font
					(size 1.27 1.27)
				)
			)
		)
		(property "Value" ""
			(at 0 0 90)
			(layer "F.Fab")
			(effects
				(font
					(size 1.27 1.27)
				)
			)
		)
		(duplicate_pad_numbers_are_jumpers no)
		(fp_poly
			(pts
				(xy 0.3048 -0.1016) (xy 0.3048 0.9906) (xy -0.3048 0.9906) (xy -0.3048 -0.1016)
			)
			(stroke
				(width 0)
				(type default)
			)
			(fill no)
			(layer "F.CrtYd")
		)
		(fp_line
			(start 0.3048 -0.1016)
			(end -0.3048 -0.1016)
			(stroke
				(width 0.1)
				(type default)
			)
			(layer "F.Fab")
		)
		(fp_line
			(start -0.3048 -0.1016)
			(end -0.3048 0.9906)
			(stroke
				(width 0.1)
				(type default)
			)
			(layer "F.Fab")
		)
		(fp_line
			(start 0.3048 0.9906)
			(end 0.3048 -0.1016)
			(stroke
				(width 0.1)
				(type default)
			)
			(layer "F.Fab")
		)
		(fp_line
			(start -0.3048 0.9906)
			(end 0.3048 0.9906)
			(stroke
				(width 0.1)
				(type default)
			)
			(layer "F.Fab")
		)
		(pad "1" smd rect
			(at 0 0 90)
			(size 0.508 0.508)
			(layers "F.Cu" "F.Mask" "F.Paste")
			(net "M_D_VREF")
		)
		(pad "2" smd rect
			(at 0 0.889 90)
			(size 0.508 0.508)
			(layers "F.Cu" "F.Mask" "F.Paste")
			(net "GND")
		)
		(zone
			(layer "F.Cu")
			(hatch none 0.5)
			(connect_pads
				(clearance 0)
			)
			(min_thickness 0.25)
			(keepout
				(tracks allowed)
				(vias not_allowed)
				(pads allowed)
				(copperpour not_allowed)
				(footprints allowed)
			)
			(placement
				(enabled no)
				(sheetname "")
			)
			(fill
				(thermal_gap 0.5)
				(thermal_bridge_width 0.5)
				(island_removal_mode 0)
			)
			(polygon
				(pts
					(xy 195.8086 -129.9972) (xy 195.8086 -130.5052) (xy 196.1896 -130.5052) (xy 196.1896 -129.9972)
				)
			)
		)
		(zone
			(layer "F.Cu")
			(hatch none 0.5)
			(connect_pads
				(clearance 0)
			)
			(min_thickness 0.25)
			(keepout
				(tracks not_allowed)
				(vias allowed)
				(pads allowed)
				(copperpour not_allowed)
				(footprints allowed)
			)
			(placement
				(enabled no)
				(sheetname "")
			)
			(fill
				(thermal_gap 0.5)
				(thermal_bridge_width 0.5)
				(island_removal_mode 0)
			)
			(polygon
				(pts
					(xy 196.1896 -129.9972) (xy 196.1896 -130.5052) (xy 195.8086 -130.5052) (xy 195.8086 -129.9972)
				)
			)
		)
	)
	(footprint ""
		(layer "F.Cu")
		(at 168.656 -86.868 180)
		(property "Reference" "R4D4"
			(at 0 0 180)
			(layer "F.SilkS")
			(hide yes)
			(effects
				(font
					(size 1.27 1.27)
				)
			)
		)
		(property "Value" ""
			(at 0 0 180)
			(layer "F.Fab")
			(effects
				(font
					(size 1.27 1.27)
				)
			)
		)
		(duplicate_pad_numbers_are_jumpers no)
		(fp_poly
			(pts
				(xy -0.2794 -0.1016) (xy 0.2794 -0.1016) (xy 0.2794 0.9906) (xy -0.2794 0.9906)
			)
			(stroke
				(width 0)
				(type default)
			)
			(fill no)
			(layer "F.CrtYd")
		)
		(fp_line
			(start 0.2794 0.9906)
			(end 0.2794 -0.1016)
			(stroke
				(width 0.1)
				(type default)
			)
			(layer "F.Fab")
		)
		(fp_line
			(start 0.2794 -0.1016)
			(end -0.2794 -0.1016)
			(stroke
				(width 0.1)
				(type default)
			)
			(layer "F.Fab")
		)
		(fp_line
			(start -0.2794 0.9906)
			(end 0.2794 0.9906)
			(stroke
				(width 0.1)
				(type default)
			)
			(layer "F.Fab")
		)
		(fp_line
			(start -0.2794 -0.1016)
			(end -0.2794 0.9906)
			(stroke
				(width 0.1)
				(type default)
			)
			(layer "F.Fab")
		)
		(pad "1" smd rect
			(at 0 0 180)
			(size 0.508 0.508)
			(layers "F.Cu" "F.Mask" "F.Paste")
			(net "CLK_100M_CPU1_BCLK0_R_DP")
		)
		(pad "2" smd rect
			(at 0 0.889 180)
			(size 0.508 0.508)
			(layers "F.Cu" "F.Mask" "F.Paste")
			(net "CLK_100M_CPU1_BCLK0_DP")
		)
		(zone
			(layer "F.Cu")
			(hatch none 0.5)
			(connect_pads
				(clearance 0)
			)
			(min_thickness 0.25)
			(keepout
				(tracks not_allowed)
				(vias allowed)
				(pads allowed)
				(copperpour not_allowed)
				(footprints allowed)
			)
			(placement
				(enabled no)
				(sheetname "")
			)
			(fill
				(thermal_gap 0.5)
				(thermal_bridge_width 0.5)
				(island_removal_mode 0)
			)
			(polygon
				(pts
					(xy 168.91 -87.503) (xy 168.402 -87.503) (xy 168.402 -87.122) (xy 168.91 -87.122)
				)
			)
		)
		(zone
			(layer "F.Cu")
			(hatch none 0.5)
			(connect_pads
				(clearance 0)
			)
			(min_thickness 0.25)
			(keepout
				(tracks allowed)
				(vias not_allowed)
				(pads allowed)
				(copperpour not_allowed)
				(footprints allowed)
			)
			(placement
				(enabled no)
				(sheetname "")
			)
			(fill
				(thermal_gap 0.5)
				(thermal_bridge_width 0.5)
				(island_removal_mode 0)
			)
			(polygon
				(pts
					(xy 168.91 -87.122) (xy 168.402 -87.122) (xy 168.402 -87.503) (xy 168.91 -87.503)
				)
			)
		)
	)
	(footprint ""
		(layer "F.Cu")
		(at 437.7055 -14.605 -90)
		(property "Reference" "R1U55"
			(at 0 0 270)
			(layer "F.SilkS")
			(hide yes)
			(effects
				(font
					(size 1.27 1.27)
				)
			)
		)
		(property "Value" ""
			(at 0 0 270)
			(layer "F.Fab")
			(effects
				(font
					(size 1.27 1.27)
				)
			)
		)
		(duplicate_pad_numbers_are_jumpers no)
		(fp_poly
			(pts
				(xy -0.2794 -0.1016) (xy 0.2794 -0.1016) (xy 0.2794 0.9906) (xy -0.2794 0.9906)
			)
			(stroke
				(width 0)
				(type default)
			)
			(fill no)
			(layer "F.CrtYd")
		)
		(fp_line
			(start -0.2794 0.9906)
			(end 0.2794 0.9906)
			(stroke
				(width 0.1)
				(type default)
			)
			(layer "F.Fab")
		)
		(fp_line
			(start 0.2794 0.9906)
			(end 0.2794 -0.1016)
			(stroke
				(width 0.1)
				(type default)
			)
			(layer "F.Fab")
		)
		(fp_line
			(start -0.2794 -0.1016)
			(end -0.2794 0.9906)
			(stroke
				(width 0.1)
				(type default)
			)
			(layer "F.Fab")
		)
		(fp_line
			(start 0.2794 -0.1016)
			(end -0.2794 -0.1016)
			(stroke
				(width 0.1)
				(type default)
			)
			(layer "F.Fab")
		)
		(pad "1" smd rect
			(at 0 0 270)
			(size 0.508 0.508)
			(layers "F.Cu" "F.Mask" "F.Paste")
			(net "H_CPU1_MEMGHJ_MEMHOT_G_N")
		)
		(pad "2" smd rect
			(at 0 0.889 270)
			(size 0.508 0.508)
			(layers "F.Cu" "F.Mask" "F.Paste")
			(net "H_CPU1_MEMGHJ_MEMHOT_G_PCH_N")
		)
		(zone
			(layer "F.Cu")
			(hatch none 0.5)
			(connect_pads
				(clearance 0)
			)
			(min_thickness 0.25)
			(keepout
				(tracks not_allowed)
				(vias allowed)
				(pads allowed)
				(copperpour not_allowed)
				(footprints allowed)
			)
			(placement
				(enabled no)
				(sheetname "")
			)
			(fill
				(thermal_gap 0.5)
				(thermal_bridge_width 0.5)
				(island_removal_mode 0)
			)
			(polygon
				(pts
					(xy 437.0705 -14.859) (xy 437.0705 -14.351) (xy 437.4515 -14.351) (xy 437.4515 -14.859)
				)
			)
		)
		(zone
			(layer "F.Cu")
			(hatch none 0.5)
			(connect_pads
				(clearance 0)
			)
			(min_thickness 0.25)
			(keepout
				(tracks allowed)
				(vias not_allowed)
				(pads allowed)
				(copperpour not_allowed)
				(footprints allowed)
			)
			(placement
				(enabled no)
				(sheetname "")
			)
			(fill
				(thermal_gap 0.5)
				(thermal_bridge_width 0.5)
				(island_removal_mode 0)
			)
			(polygon
				(pts
					(xy 437.4515 -14.859) (xy 437.4515 -14.351) (xy 437.0705 -14.351) (xy 437.0705 -14.859)
				)
			)
		)
	)
	(footprint ""
		(layer "F.Cu")
		(at 412.742888 -48.071024 180)
		(property "Reference" "R25W141"
			(at -0.8382 -0.67818 180)
			(unlocked yes)
			(layer "F.SilkS")
			(effects
				(font
					(size 0.4064 0.254)
					(thickness 0.1524)
				)
				(justify left)
			)
		)
		(property "Value" ""
			(at 0 0 180)
			(layer "F.Fab")
			(effects
				(font
					(size 1.27 1.27)
				)
			)
		)
		(duplicate_pad_numbers_are_jumpers no)
		(fp_poly
			(pts
				(xy -0.2794 -0.1016) (xy 0.2794 -0.1016) (xy 0.2794 0.9906) (xy -0.2794 0.9906)
			)
			(stroke
				(width 0)
				(type default)
			)
			(fill no)
			(layer "F.CrtYd")
		)
		(fp_line
			(start 0.2794 0.9906)
			(end 0.2794 -0.1016)
			(stroke
				(width 0.1)
				(type default)
			)
			(layer "F.Fab")
		)
		(fp_line
			(start 0.2794 -0.1016)
			(end -0.2794 -0.1016)
			(stroke
				(width 0.1)
				(type default)
			)
			(layer "F.Fab")
		)
		(fp_line
			(start -0.2794 0.9906)
			(end 0.2794 0.9906)
			(stroke
				(width 0.1)
				(type default)
			)
			(layer "F.Fab")
		)
		(fp_line
			(start -0.2794 -0.1016)
			(end -0.2794 0.9906)
			(stroke
				(width 0.1)
				(type default)
			)
			(layer "F.Fab")
		)
		(pad "1" smd rect
			(at 0 0 180)
			(size 0.508 0.508)
			(layers "F.Cu" "F.Mask" "F.Paste")
			(net "RST_PLTRST_BUF_N")
		)
		(pad "2" smd rect
			(at 0 0.889 180)
			(size 0.508 0.508)
			(layers "F.Cu" "F.Mask" "F.Paste")
			(net "RST_PLTRST_BUF_N_R")
		)
		(zone
			(layer "F.Cu")
			(hatch none 0.5)
			(connect_pads
				(clearance 0)
			)
			(min_thickness 0.25)
			(keepout
				(tracks not_allowed)
				(vias allowed)
				(pads allowed)
				(copperpour not_allowed)
				(footprints allowed)
			)
			(placement
				(enabled no)
				(sheetname "")
			)
			(fill
				(thermal_gap 0.5)
				(thermal_bridge_width 0.5)
				(island_removal_mode 0)
			)
			(polygon
				(pts
					(xy 412.996888 -48.706024) (xy 412.488888 -48.706024) (xy 412.488888 -48.325024) (xy 412.996888 -48.325024)
				)
			)
		)
		(zone
			(layer "F.Cu")
			(hatch none 0.5)
			(connect_pads
				(clearance 0)
			)
			(min_thickness 0.25)
			(keepout
				(tracks allowed)
				(vias not_allowed)
				(pads allowed)
				(copperpour not_allowed)
				(footprints allowed)
			)
			(placement
				(enabled no)
				(sheetname "")
			)
			(fill
				(thermal_gap 0.5)
				(thermal_bridge_width 0.5)
				(island_removal_mode 0)
			)
			(polygon
				(pts
					(xy 412.996888 -48.325024) (xy 412.488888 -48.325024) (xy 412.488888 -48.706024) (xy 412.996888 -48.706024)
				)
			)
		)
	)
	(footprint ""
		(layer "F.Cu")
		(at 80.739488 -140.208 -90)
		(property "Reference" "C2A9"
			(at 1.848866 0.752348 270)
			(unlocked yes)
			(layer "F.SilkS")
			(effects
				(font
					(size 1.27 0.9652)
					(thickness 0.1524)
				)
			)
		)
		(property "Value" ""
			(at 0 0 270)
			(layer "F.Fab")
			(effects
				(font
					(size 1.27 1.27)
				)
			)
		)
		(duplicate_pad_numbers_are_jumpers no)
		(fp_rect
			(start -0.500126 1.598422)
			(end 0.500126 -0.201422)
			(stroke
				(width 0)
				(type default)
			)
			(fill no)
			(layer "F.CrtYd")
		)
		(fp_line
			(start -0.500126 1.598422)
			(end -0.500126 -0.201422)
			(stroke
				(width 0.1)
				(type default)
			)
			(layer "F.Fab")
		)
		(fp_line
			(start 0.500126 1.598422)
			(end -0.500126 1.598422)
			(stroke
				(width 0.1)
				(type default)
			)
			(layer "F.Fab")
		)
		(fp_line
			(start -0.500126 -0.201422)
			(end 0.500126 -0.201422)
			(stroke
				(width 0.1)
				(type default)
			)
			(layer "F.Fab")
		)
		(fp_line
			(start 0.500126 -0.201422)
			(end 0.500126 1.598422)
			(stroke
				(width 0.1)
				(type default)
			)
			(layer "F.Fab")
		)
		(pad "1" smd rect
			(at 0 0 180)
			(size 0.889 0.9906)
			(layers "F.Cu" "F.Mask" "F.Paste")
			(net "PVDDQ_KLM")
		)
		(pad "2" smd rect
			(at 0 1.397 180)
			(size 0.889 0.9906)
			(layers "F.Cu" "F.Mask" "F.Paste")
			(net "GND")
		)
		(zone
			(layer "F.Cu")
			(hatch none 0.5)
			(connect_pads
				(clearance 0)
			)
			(min_thickness 0.25)
			(keepout
				(tracks allowed)
				(vias not_allowed)
				(pads allowed)
				(copperpour not_allowed)
				(footprints allowed)
			)
			(placement
				(enabled no)
				(sheetname "")
			)
			(fill
				(thermal_gap 0.5)
				(thermal_bridge_width 0.5)
				(island_removal_mode 0)
			)
			(polygon
				(pts
					(xy 79.786988 -140.7033) (xy 79.786988 -139.7127) (xy 80.294988 -139.7127) (xy 80.294988 -140.7033)
				)
			)
		)
		(zone
			(layer "F.Cu")
			(hatch none 0.5)
			(connect_pads
				(clearance 0)
			)
			(min_thickness 0.25)
			(keepout
				(tracks not_allowed)
				(vias allowed)
				(pads allowed)
				(copperpour not_allowed)
				(footprints allowed)
			)
			(placement
				(enabled no)
				(sheetname "")
			)
			(fill
				(thermal_gap 0.5)
				(thermal_bridge_width 0.5)
				(island_removal_mode 0)
			)
			(polygon
				(pts
					(xy 79.786988 -140.7033) (xy 79.786988 -139.7127) (xy 80.294988 -139.7127) (xy 80.294988 -140.7033)
				)
			)
		)
	)
)
